(kicad_pcb
	(version 20260206)
	(generator "pcbnew")
	(generator_version "10.0")
	(general
		(thickness 1.6)
		(legacy_teardrops no)
	)
	(paper "A4")
	(title_block
		(title "Bryce Canyon_R.DPB_16317-1_OCP.brd")
		(comment 1 "Bryce Canyon / footprints 2087-2092 of 2099")
	)
	(layers
		(0 "F.Cu" signal "TOP")
		(4 "In1.Cu" signal "L2GND")
		(6 "In2.Cu" signal "L3")
		(8 "In3.Cu" signal "L4VCC")
		(10 "In4.Cu" signal "L5VCC")
		(12 "In5.Cu" signal "L6")
		(14 "In6.Cu" signal "L7GND")
		(2 "B.Cu" signal "BOTTOM")
		(9 "F.Adhes" user "F.Adhesive")
		(11 "B.Adhes" user "B.Adhesive")
		(13 "F.Paste" user "Package Geometry/Pastemask Top")
		(15 "B.Paste" user "Package Geometry/Pastemask Bottom")
		(5 "F.SilkS" user "Ref Des/Silkscreen Top")
		(7 "B.SilkS" user "Ref Des/Silkscreen Bottom")
		(1 "F.Mask" user "Board Geometry/Soldermask Top")
		(3 "B.Mask" user "Board Geometry/Soldermask Bottom")
		(17 "Dwgs.User" user "User.Drawings")
		(19 "Cmts.User" user "User.Comments")
		(21 "Eco1.User" user "User.Eco1")
		(23 "Eco2.User" user "User.Eco2")
		(25 "Edge.Cuts" user "Board Geometry/Outline")
		(27 "Margin" user)
		(31 "F.CrtYd" user "Package Geometry/Place Bound Top")
		(29 "B.CrtYd" user "Package Geometry/Place Bound Bottom")
		(35 "F.Fab" user "Ref Des/Assembly Top")
		(33 "B.Fab" user "Ref Des/Assembly Bottom")
	)
	(footprint ""
		(layer "B.Cu")
		(at 218.44 -355.473 180)
		(property "Reference" "C515"
			(at 0 0 0)
			(layer "B.SilkS")
			(hide yes)
			(effects
				(font
					(size 1.27 1.27)
				)
				(justify mirror)
			)
		)
		(property "Value" "SC22U25V6KX-2-GP-U"
			(at 2.860802 -5.279644 180)
			(unlocked yes)
			(layer "B.Fab")
			(hide yes)
			(effects
				(font
					(size 1.016 1.016)
					(thickness 0.1524)
				)
				(justify mirror)
			)
		)
		(property "Device Type" "C1206-TO0D3H75"
			(at 2.860802 -6.803644 180)
			(unlocked yes)
			(layer "B.Fab")
			(hide yes)
			(effects
				(font
					(size 1.016 1.016)
					(thickness 0.1524)
				)
				(justify mirror)
			)
		)
		(duplicate_pad_numbers_are_jumpers no)
		(fp_line
			(start 1.3081 2.3749)
			(end 1.3081 -2.3749)
			(stroke
				(width 0.1524)
				(type default)
			)
			(layer "B.SilkS")
		)
		(fp_line
			(start 1.3081 -2.3749)
			(end -1.3081 -2.3749)
			(stroke
				(width 0.1524)
				(type default)
			)
			(layer "B.SilkS")
		)
		(fp_line
			(start -1.3081 2.3749)
			(end 1.3081 2.3749)
			(stroke
				(width 0.1524)
				(type default)
			)
			(layer "B.SilkS")
		)
		(fp_line
			(start -1.3081 -2.3749)
			(end -1.3081 2.3749)
			(stroke
				(width 0.1524)
				(type default)
			)
			(layer "B.SilkS")
		)
		(fp_rect
			(start 0.8001 1.6002)
			(end -0.8001 -1.6002)
			(stroke
				(width 0)
				(type default)
			)
			(fill no)
			(layer "B.CrtYd")
		)
		(fp_poly
			(pts
				(xy 1.5621 2.4511) (xy 1.5621 1.6002) (xy -0.8001 1.6002) (xy -0.8001 -1.6002) (xy 0.8001 -1.6002)
				(xy 0.8001 1.5875) (xy 1.5621 1.5875) (xy 1.5621 -2.4511) (xy -1.5621 -2.4511) (xy -1.5621 2.4511)
			)
			(stroke
				(width 0)
				(type default)
			)
			(fill no)
			(layer "B.CrtYd")
		)
		(fp_rect
			(start 1.5621 2.4511)
			(end -1.5621 -2.4511)
			(stroke
				(width 0)
				(type default)
			)
			(fill no)
			(layer "B.Fab")
		)
		(pad "1" smd rect
			(at 0 -1.392936)
			(size 2.1082 1.4478)
			(layers "B.Cu" "B.Mask" "B.Paste")
			(net "P12V_IN")
		)
		(pad "2" smd rect
			(at 0 1.392936)
			(size 2.1082 1.4478)
			(layers "B.Cu" "B.Mask" "B.Paste")
			(net "GND")
		)
	)
	(footprint ""
		(layer "B.Cu")
		(at 65.945258 -108.876846)
		(property "Reference" "TC12"
			(at 0 0 0)
			(layer "B.SilkS")
			(hide yes)
			(effects
				(font
					(size 1.27 1.27)
				)
				(justify mirror)
			)
		)
		(property "Value" "ST220U10VDM-LGP"
			(at 0 -9.6012 0)
			(unlocked yes)
			(layer "B.Fab")
			(hide yes)
			(effects
				(font
					(size 1.016 1.016)
					(thickness 0.1524)
				)
				(justify mirror)
			)
		)
		(property "Device Type" "CT7343H119"
			(at 0 -11.1252 0)
			(unlocked yes)
			(layer "B.Fab")
			(hide yes)
			(effects
				(font
					(size 1.016 1.016)
					(thickness 0.1524)
				)
				(justify mirror)
			)
		)
		(duplicate_pad_numbers_are_jumpers no)
		(fp_line
			(start -2.286 -4.8768)
			(end 2.286 -4.8768)
			(stroke
				(width 0.1524)
				(type default)
			)
			(layer "B.SilkS")
		)
		(fp_line
			(start -2.286 -2.032)
			(end -2.286 -4.8768)
			(stroke
				(width 0.1524)
				(type default)
			)
			(layer "B.SilkS")
		)
		(fp_line
			(start -2.286 2.032)
			(end -2.286 4.8768)
			(stroke
				(width 0.1524)
				(type default)
			)
			(layer "B.SilkS")
		)
		(fp_line
			(start -2.286 4.8768)
			(end 2.286 4.8768)
			(stroke
				(width 0.1524)
				(type default)
			)
			(layer "B.SilkS")
		)
		(fp_line
			(start -2.1082 -4.699)
			(end 2.1082 -4.699)
			(stroke
				(width 0.508)
				(type default)
			)
			(layer "B.SilkS")
		)
		(fp_line
			(start 2.286 -4.8768)
			(end 2.286 -2.032)
			(stroke
				(width 0.1524)
				(type default)
			)
			(layer "B.SilkS")
		)
		(fp_line
			(start 2.286 4.8768)
			(end 2.286 2.032)
			(stroke
				(width 0.1524)
				(type default)
			)
			(layer "B.SilkS")
		)
		(fp_rect
			(start 2.1463 3.6449)
			(end -2.1463 -3.6449)
			(stroke
				(width 0)
				(type default)
			)
			(fill no)
			(layer "B.CrtYd")
		)
		(fp_poly
			(pts
				(xy 2.54 4.953) (xy 2.54 4.2926) (xy 3.81 4.2926) (xy 3.81 -4.2926) (xy 2.54 -4.2926) (xy 2.54 -4.953)
				(xy -2.54 -4.953) (xy -2.54 -4.2926) (xy -3.81 -4.2926) (xy -3.81 -1.6256) (xy -2.1463 -1.6256)
				(xy -2.1463 -3.6449) (xy 2.1463 -3.6449) (xy 2.1463 3.6449) (xy -2.1463 3.6449) (xy -2.1463 -1.6129)
				(xy -3.81 -1.6129) (xy -3.81 4.2926) (xy -2.54 4.2926) (xy -2.54 4.953)
			)
			(stroke
				(width 0)
				(type default)
			)
			(fill no)
			(layer "B.CrtYd")
		)
		(fp_rect
			(start -2.54 4.2926)
			(end -3.81 -4.2926)
			(stroke
				(width 0)
				(type default)
			)
			(fill no)
			(layer "B.Fab")
		)
		(fp_rect
			(start 2.54 4.953)
			(end -2.54 -4.953)
			(stroke
				(width 0)
				(type default)
			)
			(fill no)
			(layer "B.Fab")
		)
		(fp_rect
			(start 3.81 4.2926)
			(end 2.54 -4.2926)
			(stroke
				(width 0)
				(type default)
			)
			(fill no)
			(layer "B.Fab")
		)
		(pad "1" smd rect
			(at 0 -3.1496 180)
			(size 2.413 2.286)
			(layers "B.Cu" "B.Mask" "B.Paste")
			(net "P5V_B_2")
		)
		(pad "2" smd rect
			(at 0 3.1496 180)
			(size 2.413 2.286)
			(layers "B.Cu" "B.Mask" "B.Paste")
			(net "GND")
		)
		(zone
			(layer "B.Cu")
			(hatch none 0.5)
			(connect_pads
				(clearance 0)
			)
			(min_thickness 0.25)
			(keepout
				(tracks allowed)
				(vias not_allowed)
				(pads allowed)
				(copperpour not_allowed)
				(footprints allowed)
			)
			(placement
				(enabled no)
				(sheetname "")
			)
			(fill
				(thermal_gap 0.5)
				(thermal_bridge_width 0.5)
				(island_removal_mode 0)
			)
			(polygon
				(pts
					(xy 64.433958 -110.565946) (xy 64.433958 -113.474246) (xy 67.456558 -113.474246) (xy 67.456558 -110.578646)
					(xy 67.456558 -110.248446) (xy 64.433958 -110.248446)
				)
			)
		)
		(zone
			(layer "B.Cu")
			(hatch none 0.5)
			(connect_pads
				(clearance 0)
			)
			(min_thickness 0.25)
			(keepout
				(tracks allowed)
				(vias not_allowed)
				(pads allowed)
				(copperpour not_allowed)
				(footprints allowed)
			)
			(placement
				(enabled no)
				(sheetname "")
			)
			(fill
				(thermal_gap 0.5)
				(thermal_bridge_width 0.5)
				(island_removal_mode 0)
			)
			(polygon
				(pts
					(xy 67.456558 -104.279446) (xy 64.433958 -104.279446) (xy 64.433958 -107.175046) (xy 64.433958 -107.505246)
					(xy 67.456558 -107.505246) (xy 67.456558 -107.175046)
				)
			)
		)
	)
	(footprint ""
		(layer "B.Cu")
		(at 44.643802 -228.35235 180)
		(property "Reference" "C632"
			(at 0 0 0)
			(layer "B.SilkS")
			(hide yes)
			(effects
				(font
					(size 1.27 1.27)
				)
				(justify mirror)
			)
		)
		(property "Value" "SC10U16V5KX-7-GP-U"
			(at 0.0762 -6.1214 180)
			(unlocked yes)
			(layer "B.Fab")
			(hide yes)
			(effects
				(font
					(size 1.016 1.016)
					(thickness 0.1524)
				)
				(justify mirror)
			)
		)
		(property "Device Type" "C805H58"
			(at 0.0762 -8.1534 180)
			(unlocked yes)
			(layer "B.Fab")
			(hide yes)
			(effects
				(font
					(size 1.016 1.016)
					(thickness 0.1524)
				)
				(justify mirror)
			)
		)
		(duplicate_pad_numbers_are_jumpers no)
		(fp_line
			(start -0.635 0)
			(end 0.635 0)
			(stroke
				(width 0.508)
				(type default)
			)
			(layer "B.SilkS")
		)
		(fp_rect
			(start 0.9652 1.778)
			(end -0.9652 -1.778)
			(stroke
				(width 0)
				(type default)
			)
			(fill no)
			(layer "B.CrtYd")
		)
		(fp_poly
			(pts
				(xy 0.9652 -1.778) (xy -0.9652 -1.778) (xy -0.9652 1.778) (xy 0.9652 1.778)
			)
			(stroke
				(width 0)
				(type default)
			)
			(fill no)
			(layer "B.Fab")
		)
		(pad "1" smd rect
			(at 0 -0.9652)
			(size 1.397 1.143)
			(layers "B.Cu" "B.Mask" "B.Paste")
			(net "P5V_B_1")
		)
		(pad "2" smd rect
			(at 0 0.9652)
			(size 1.397 1.143)
			(layers "B.Cu" "B.Mask" "B.Paste")
			(net "GND")
		)
	)
	(footprint ""
		(layer "B.Cu")
		(at 201.89952 -353.760786 90)
		(property "Reference" "Q198"
			(at 0 0 90)
			(layer "B.SilkS")
			(hide yes)
			(effects
				(font
					(size 1.27 1.27)
				)
				(justify mirror)
			)
		)
		(property "Value" "IRFH8201TRPBF-GP"
			(at 4.2164 -4.3688 90)
			(unlocked yes)
			(layer "B.Fab")
			(hide yes)
			(effects
				(font
					(size 1.016 1.016)
					(thickness 0.1524)
				)
				(justify mirror)
			)
		)
		(property "Device Type" "PPAK-5PH42"
			(at 4.2164 -5.8928 90)
			(unlocked yes)
			(layer "B.Fab")
			(hide yes)
			(effects
				(font
					(size 1.016 1.016)
					(thickness 0.1524)
				)
				(justify mirror)
			)
		)
		(duplicate_pad_numbers_are_jumpers no)
		(fp_line
			(start 2.8956 -2.794)
			(end -2.8956 -2.794)
			(stroke
				(width 0.1524)
				(type default)
			)
			(layer "B.SilkS")
		)
		(fp_line
			(start -2.8956 -2.794)
			(end -2.8956 4.826)
			(stroke
				(width 0.1524)
				(type default)
			)
			(layer "B.SilkS")
		)
		(fp_line
			(start 2.8956 4.826)
			(end 2.8956 -2.794)
			(stroke
				(width 0.1524)
				(type default)
			)
			(layer "B.SilkS")
		)
		(fp_line
			(start -2.8956 4.826)
			(end 2.8956 4.826)
			(stroke
				(width 0.1524)
				(type default)
			)
			(layer "B.SilkS")
		)
		(fp_line
			(start 3.0353 4.9276)
			(end 3.0353 3.9624)
			(stroke
				(width 0.3302)
				(type default)
			)
			(layer "B.SilkS")
		)
		(fp_line
			(start 1.9431 4.9276)
			(end 3.0353 4.9276)
			(stroke
				(width 0.3302)
				(type default)
			)
			(layer "B.SilkS")
		)
		(fp_poly
			(pts
				(xy 2.3622 5.334) (xy 1.4986 5.334) (xy 1.9304 4.9022)
			)
			(stroke
				(width 0)
				(type default)
			)
			(fill yes)
			(layer "B.SilkS")
		)
		(fp_poly
			(pts
				(xy 2.6416 -0.3556) (xy 0.3556 -0.3556) (xy 0.3556 -2.54) (xy 2.6416 -2.54)
			)
			(stroke
				(width 0)
				(type default)
			)
			(fill yes)
			(layer "B.Paste")
		)
		(fp_poly
			(pts
				(xy -0.3556 -0.3556) (xy -2.6416 -0.3556) (xy -2.6416 -2.54) (xy -0.3556 -2.54)
			)
			(stroke
				(width 0)
				(type default)
			)
			(fill yes)
			(layer "B.Paste")
		)
		(fp_poly
			(pts
				(xy 2.6416 2.54) (xy 0.3556 2.54) (xy 0.3556 0.3556) (xy 2.6416 0.3556)
			)
			(stroke
				(width 0)
				(type default)
			)
			(fill yes)
			(layer "B.Paste")
		)
		(fp_poly
			(pts
				(xy -0.3556 2.54) (xy -2.6416 2.54) (xy -2.6416 0.3556) (xy -0.3556 0.3556)
			)
			(stroke
				(width 0)
				(type default)
			)
			(fill yes)
			(layer "B.Paste")
		)
		(fp_rect
			(start 2.5781 3.9878)
			(end -2.5781 -2.1082)
			(stroke
				(width 0)
				(type default)
			)
			(fill no)
			(layer "B.CrtYd")
		)
		(fp_poly
			(pts
				(xy 3.1496 5.08) (xy 3.1496 -3.048) (xy -3.1496 -3.048) (xy -3.1496 3.9751) (xy -2.5781 3.9751)
				(xy -2.5781 -2.1082) (xy 2.5781 -2.1082) (xy 2.5781 3.9878) (xy -3.1496 3.9878) (xy -3.1496 5.08)
			)
			(stroke
				(width 0)
				(type default)
			)
			(fill no)
			(layer "B.CrtYd")
		)
		(fp_rect
			(start 3.1496 5.08)
			(end -3.1496 -3.048)
			(stroke
				(width 0)
				(type default)
			)
			(fill no)
			(layer "B.Fab")
		)
		(pad "1" smd rect
			(at 1.905 3.81 270)
			(size 0.762 1.524)
			(layers "B.Cu" "B.Mask" "B.Paste")
			(net "P12V_IN")
		)
		(pad "2" smd rect
			(at 0.635 3.81 270)
			(size 0.762 1.524)
			(layers "B.Cu" "B.Mask" "B.Paste")
			(net "P12V_IN")
		)
		(pad "3" smd rect
			(at -0.635 3.81 270)
			(size 0.762 1.524)
			(layers "B.Cu" "B.Mask" "B.Paste")
			(net "P12V_IN")
		)
		(pad "4" smd rect
			(at -1.905 3.81 270)
			(size 0.762 1.524)
			(layers "B.Cu" "B.Mask" "B.Paste")
			(net "MB0_12V_CTRL_GATE5")
		)
		(pad "5" smd rect
			(at 0 0 270)
			(size 5.2832 5.08)
			(layers "B.Cu" "B.Mask" "B.Paste")
			(net "MB0_P12V_IN_R")
		)
		(pad "6" smd rect
			(at -0.635 -2.032 270)
			(size 0.0254 0.0254)
			(layers "B.Cu" "B.Mask" "B.Paste")
			(net "MB0_P12V_IN_R")
		)
		(pad "7" smd rect
			(at 0.635 -2.032 270)
			(size 0.0254 0.0254)
			(layers "B.Cu" "B.Mask" "B.Paste")
			(net "MB0_P12V_IN_R")
		)
		(pad "8" smd rect
			(at 1.905 -2.032 270)
			(size 0.0254 0.0254)
			(layers "B.Cu" "B.Mask" "B.Paste")
			(net "MB0_P12V_IN_R")
		)
	)
	(footprint ""
		(layer "B.Cu")
		(at 47.439072 -118.35892 180)
		(property "Reference" "R1130"
			(at 0 0 0)
			(layer "B.SilkS")
			(hide yes)
			(effects
				(font
					(size 1.27 1.27)
				)
				(justify mirror)
			)
		)
		(property "Value" "10KR2F-2-GP"
			(at -0.064008 -3.993896 180)
			(unlocked yes)
			(layer "B.Fab")
			(hide yes)
			(effects
				(font
					(size 1.016 1.016)
					(thickness 0.1524)
				)
				(justify mirror)
			)
		)
		(property "Device Type" "R402H16"
			(at -0.064008 -5.517896 180)
			(unlocked yes)
			(layer "B.Fab")
			(hide yes)
			(effects
				(font
					(size 1.016 1.016)
					(thickness 0.1524)
				)
				(justify mirror)
			)
		)
		(duplicate_pad_numbers_are_jumpers no)
		(fp_line
			(start 0.508 -0.9398)
			(end 0.508 0.9398)
			(stroke
				(width 0.1524)
				(type default)
			)
			(layer "B.SilkS")
		)
		(fp_line
			(start -0.508 -0.9398)
			(end 0.508 -0.9398)
			(stroke
				(width 0.1524)
				(type default)
			)
			(layer "B.SilkS")
		)
		(fp_rect
			(start 0.508 0.9398)
			(end -0.508 -0.9398)
			(stroke
				(width 0)
				(type default)
			)
			(fill no)
			(layer "B.CrtYd")
		)
		(fp_rect
			(start 0.508 0.9398)
			(end -0.508 -0.9398)
			(stroke
				(width 0)
				(type default)
			)
			(fill no)
			(layer "B.Fab")
		)
		(pad "1" smd custom
			(at 0 -0.4445)
			(size 0.1397 0.1397)
			(layers "B.Cu" "B.Mask" "B.Paste")
			(net "P5V_B_2_VFB")
			(options
				(clearance outline)
				(anchor circle)
			)
			(primitives
				(gr_poly
					(pts
						(arc
							(start -0.1778 0.2794)
							(mid -0.249642 0.249642)
							(end -0.2794 0.1778)
						)
						(arc
							(start -0.2794 -0.1778)
							(mid -0.249642 -0.249642)
							(end -0.1778 -0.2794)
						)
						(arc
							(start 0.1778 -0.2794)
							(mid 0.249642 -0.249642)
							(end 0.2794 -0.1778)
						)
						(arc
							(start 0.2794 0.1778)
							(mid 0.249642 0.249642)
							(end 0.1778 0.2794)
						)
					)
					(width 0)
					(fill yes)
				)
			)
		)
		(pad "2" smd custom
			(at 0 0.4445)
			(size 0.1397 0.1397)
			(layers "B.Cu" "B.Mask" "B.Paste")
			(net "AGND_P5V_B_2")
			(options
				(clearance outline)
				(anchor circle)
			)
			(primitives
				(gr_poly
					(pts
						(arc
							(start -0.1778 0.2794)
							(mid -0.249642 0.249642)
							(end -0.2794 0.1778)
						)
						(arc
							(start -0.2794 -0.1778)
							(mid -0.249642 -0.249642)
							(end -0.1778 -0.2794)
						)
						(arc
							(start 0.1778 -0.2794)
							(mid 0.249642 -0.249642)
							(end 0.2794 -0.1778)
						)
						(arc
							(start 0.2794 0.1778)
							(mid 0.249642 0.249642)
							(end 0.1778 0.2794)
						)
					)
					(width 0)
					(fill yes)
				)
			)
		)
	)
	(footprint ""
		(layer "B.Cu")
		(at 170.04538 -372.364)
		(property "Reference" "C543"
			(at 0 0 0)
			(layer "B.SilkS")
			(hide yes)
			(effects
				(font
					(size 1.27 1.27)
				)
				(justify mirror)
			)
		)
		(property "Value" "SCD015U25V2KX-GP"
			(at -1.1811 -2.7051 0)
			(unlocked yes)
			(layer "B.Fab")
			(hide yes)
			(effects
				(font
					(size 1.016 1.016)
					(thickness 0.1524)
				)
				(justify mirror)
			)
		)
		(property "Device Type" "C402H22"
			(at -1.1811 -4.2291 0)
			(unlocked yes)
			(layer "B.Fab")
			(hide yes)
			(effects
				(font
					(size 1.016 1.016)
					(thickness 0.1524)
				)
				(justify mirror)
			)
		)
		(duplicate_pad_numbers_are_jumpers no)
		(fp_rect
			(start 0.4318 0.9525)
			(end -0.4318 -0.9525)
			(stroke
				(width 0)
				(type default)
			)
			(fill no)
			(layer "B.CrtYd")
		)
		(fp_rect
			(start 0.4318 0.9525)
			(end -0.4318 -0.9525)
			(stroke
				(width 0)
				(type default)
			)
			(fill no)
			(layer "B.Fab")
		)
		(pad "1" smd custom
			(at 0 -0.4445 180)
			(size 0.1524 0.1524)
			(layers "B.Cu" "B.Mask" "B.Paste")
			(net "MB0_CM_SENSE_P")
			(options
				(clearance outline)
				(anchor circle)
			)
			(primitives
				(gr_poly
					(pts
						(arc
							(start 0.3048 0.2032)
							(mid 0.275042 0.275042)
							(end 0.2032 0.3048)
						)
						(arc
							(start -0.2032 0.3048)
							(mid -0.275042 0.275042)
							(end -0.3048 0.2032)
						)
						(arc
							(start -0.3048 -0.2032)
							(mid -0.275042 -0.275042)
							(end -0.2032 -0.3048)
						)
						(arc
							(start 0.2032 -0.3048)
							(mid 0.275042 -0.275042)
							(end 0.3048 -0.2032)
						)
					)
					(width 0)
					(fill yes)
				)
			)
		)
		(pad "2" smd custom
			(at 0 0.4445 180)
			(size 0.1524 0.1524)
			(layers "B.Cu" "B.Mask" "B.Paste")
			(net "MB0_CM_SENSE_N")
			(options
				(clearance outline)
				(anchor circle)
			)
			(primitives
				(gr_poly
					(pts
						(arc
							(start 0.3048 0.2032)
							(mid 0.275042 0.275042)
							(end 0.2032 0.3048)
						)
						(arc
							(start -0.2032 0.3048)
							(mid -0.275042 0.275042)
							(end -0.3048 0.2032)
						)
						(arc
							(start -0.3048 -0.2032)
							(mid -0.275042 -0.275042)
							(end -0.2032 -0.3048)
						)
						(arc
							(start 0.2032 -0.3048)
							(mid 0.275042 -0.275042)
							(end 0.3048 -0.2032)
						)
					)
					(width 0)
					(fill yes)
				)
			)
		)
	)
)
